# BASEBOARD_FAB2 (Tioga Pass) — schematic netlist excerpt (pin names and nets, part order shuffled) for the footprints in the layout excerpt that follows; sources: Cadence DE-HDL packaged netlist, KiCad conversion of Wiwynn_Tioga_Pass_MB.brd

R7P22  RES  240 1.0% EMPTY  pkg 0402  page 90 : A = PVCCIO_CPU1 ; B = PU_CPU1_LEGACY_SKT
C5P44  CAP  100UF 4V 20% X5R  pkg 0805  page 217 : A = PVDDQ_ABC ; B = GND
C2N21  CAP  10UF 6.3V 20% X6S  pkg 0603  page 130 : A = P3V3_STBY ; B = GND

(kicad_pcb
	(version 20260206)
	(generator "pcbnew")
	(generator_version "10.0")
	(general
		(thickness 1.6)
		(legacy_teardrops no)
	)
	(paper "A4")
	(title_block
		(title "Wiwynn_Tioga_Pass_MB.brd")
		(comment 1 "Tioga Pass / footprints 2437-2439 of 4770")
	)
	(layers
		(0 "F.Cu" signal "TOP")
		(4 "In1.Cu" signal "L2GND")
		(6 "In2.Cu" signal "L3")
		(8 "In3.Cu" signal "L4GND")
		(10 "In4.Cu" signal "L5")
		(12 "In5.Cu" signal "L6GND")
		(14 "In6.Cu" signal "L7VCC")
		(16 "In7.Cu" signal "L8VCC")
		(18 "In8.Cu" signal "L9GND")
		(20 "In9.Cu" signal "L10")
		(22 "In10.Cu" signal "L11GND")
		(24 "In11.Cu" signal "L12")
		(26 "In12.Cu" signal "L13GND")
		(2 "B.Cu" signal "BOTTOM")
		(9 "F.Adhes" user "F.Adhesive")
		(11 "B.Adhes" user "B.Adhesive")
		(13 "F.Paste" user "Package Geometry/Pastemask Top")
		(15 "B.Paste" user "Package Geometry/Pastemask Bottom")
		(5 "F.SilkS" user "Ref Des/Silkscreen Top")
		(7 "B.SilkS" user "Ref Des/Silkscreen Bottom")
		(1 "F.Mask" user "Board Geometry/Soldermask Top")
		(3 "B.Mask" user "Board Geometry/Soldermask Bottom")
		(17 "Dwgs.User" user "User.Drawings")
		(19 "Cmts.User" user "User.Comments")
		(21 "Eco1.User" user "User.Eco1")
		(23 "Eco2.User" user "User.Eco2")
		(25 "Edge.Cuts" user "Board Geometry/Outline")
		(27 "Margin" user)
		(31 "F.CrtYd" user "Package Geometry/Place Bound Top")
		(29 "B.CrtYd" user "Package Geometry/Place Bound Bottom")
		(35 "F.Fab" user "Ref Des/Assembly Top")
		(33 "B.Fab" user "Ref Des/Assembly Bottom")
	)
	(footprint ""
		(layer "B.Cu")
		(at 112.378236 -68.603114 -90)
		(property "Reference" "R7P22"
			(at 0 0 90)
			(layer "B.SilkS")
			(hide yes)
			(effects
				(font
					(size 1.27 1.27)
				)
				(justify mirror)
			)
		)
		(property "Value" ""
			(at 0 0 90)
			(layer "B.Fab")
			(effects
				(font
					(size 1.27 1.27)
				)
				(justify mirror)
			)
		)
		(duplicate_pad_numbers_are_jumpers no)
		(fp_poly
			(pts
				(xy 0.2794 -0.1016) (xy -0.2794 -0.1016) (xy -0.2794 0.9906) (xy 0.2794 0.9906)
			)
			(stroke
				(width 0)
				(type default)
			)
			(fill no)
			(layer "B.CrtYd")
		)
		(fp_line
			(start -0.2794 0.9906)
			(end -0.2794 -0.1016)
			(stroke
				(width 0.1)
				(type default)
			)
			(layer "B.Fab")
		)
		(fp_line
			(start 0.2794 0.9906)
			(end -0.2794 0.9906)
			(stroke
				(width 0.1)
				(type default)
			)
			(layer "B.Fab")
		)
		(fp_line
			(start -0.2794 -0.1016)
			(end 0.2794 -0.1016)
			(stroke
				(width 0.1)
				(type default)
			)
			(layer "B.Fab")
		)
		(fp_line
			(start 0.2794 -0.1016)
			(end 0.2794 0.9906)
			(stroke
				(width 0.1)
				(type default)
			)
			(layer "B.Fab")
		)
		(pad "1" smd rect
			(at 0 0 90)
			(size 0.508 0.508)
			(layers "B.Cu" "B.Mask" "B.Paste")
			(net "PVCCIO_CPU1")
		)
		(pad "2" smd rect
			(at 0 0.889 90)
			(size 0.508 0.508)
			(layers "B.Cu" "B.Mask" "B.Paste")
			(net "PU_CPU1_LEGACY_SKT")
		)
		(zone
			(layer "B.Cu")
			(hatch none 0.5)
			(connect_pads
				(clearance 0)
			)
			(min_thickness 0.25)
			(keepout
				(tracks not_allowed)
				(vias allowed)
				(pads allowed)
				(copperpour not_allowed)
				(footprints allowed)
			)
			(placement
				(enabled no)
				(sheetname "")
			)
			(fill
				(thermal_gap 0.5)
				(thermal_bridge_width 0.5)
				(island_removal_mode 0)
			)
			(polygon
				(pts
					(xy 111.743236 -68.349114) (xy 111.743236 -68.857114) (xy 112.124236 -68.857114) (xy 112.124236 -68.349114)
				)
			)
		)
		(zone
			(layer "B.Cu")
			(hatch none 0.5)
			(connect_pads
				(clearance 0)
			)
			(min_thickness 0.25)
			(keepout
				(tracks allowed)
				(vias not_allowed)
				(pads allowed)
				(copperpour not_allowed)
				(footprints allowed)
			)
			(placement
				(enabled no)
				(sheetname "")
			)
			(fill
				(thermal_gap 0.5)
				(thermal_bridge_width 0.5)
				(island_removal_mode 0)
			)
			(polygon
				(pts
					(xy 112.124236 -68.349114) (xy 112.124236 -68.857114) (xy 111.743236 -68.857114) (xy 111.743236 -68.349114)
				)
			)
		)
	)
	(footprint ""
		(layer "B.Cu")
		(at 406.4 -105.8545 180)
		(property "Reference" "C2N21"
			(at 0 0 0)
			(layer "B.SilkS")
			(hide yes)
			(effects
				(font
					(size 1.27 1.27)
				)
				(justify mirror)
			)
		)
		(property "Value" ""
			(at 0 0 0)
			(layer "B.Fab")
			(effects
				(font
					(size 1.27 1.27)
				)
				(justify mirror)
			)
		)
		(duplicate_pad_numbers_are_jumpers no)
		(fp_poly
			(pts
				(xy 0.4953 -0.2032) (xy -0.4953 -0.2032) (xy -0.4953 1.6002) (xy 0.4953 1.6002)
			)
			(stroke
				(width 0)
				(type default)
			)
			(fill no)
			(layer "B.CrtYd")
		)
		(fp_line
			(start 0.4953 1.6002)
			(end 0.4953 -0.2032)
			(stroke
				(width 0.1)
				(type default)
			)
			(layer "B.Fab")
		)
		(fp_line
			(start 0.4953 -0.2032)
			(end -0.4953 -0.2032)
			(stroke
				(width 0.1)
				(type default)
			)
			(layer "B.Fab")
		)
		(fp_line
			(start -0.4953 1.6002)
			(end 0.4953 1.6002)
			(stroke
				(width 0.1)
				(type default)
			)
			(layer "B.Fab")
		)
		(fp_line
			(start -0.4953 -0.2032)
			(end -0.4953 1.6002)
			(stroke
				(width 0.1)
				(type default)
			)
			(layer "B.Fab")
		)
		(pad "1" smd rect
			(at 0 0)
			(size 0.762 0.889)
			(layers "B.Cu" "B.Mask" "B.Paste")
			(net "P3V3_STBY")
		)
		(pad "2" smd rect
			(at 0 1.397)
			(size 0.762 0.889)
			(layers "B.Cu" "B.Mask" "B.Paste")
			(net "GND")
		)
		(zone
			(layer "B.Cu")
			(hatch none 0.5)
			(connect_pads
				(clearance 0)
			)
			(min_thickness 0.25)
			(keepout
				(tracks not_allowed)
				(vias allowed)
				(pads allowed)
				(copperpour not_allowed)
				(footprints allowed)
			)
			(placement
				(enabled no)
				(sheetname "")
			)
			(fill
				(thermal_gap 0.5)
				(thermal_bridge_width 0.5)
				(island_removal_mode 0)
			)
			(polygon
				(pts
					(xy 406.019 -106.299) (xy 406.781 -106.299) (xy 406.781 -106.807) (xy 406.019 -106.807)
				)
			)
		)
	)
	(footprint ""
		(layer "B.Cu")
		(at 267.946886 -68.17614 180)
		(property "Reference" "C5P44"
			(at 0 0 0)
			(layer "B.SilkS")
			(hide yes)
			(effects
				(font
					(size 1.27 1.27)
				)
				(justify mirror)
			)
		)
		(property "Value" ""
			(at 0 0 0)
			(layer "B.Fab")
			(effects
				(font
					(size 1.27 1.27)
				)
				(justify mirror)
			)
		)
		(duplicate_pad_numbers_are_jumpers no)
		(fp_poly
			(pts
				(xy 0.7239 -0.2159) (xy -0.7239 -0.2159) (xy -0.7239 1.9939) (xy 0.7239 1.9939)
			)
			(stroke
				(width 0)
				(type default)
			)
			(fill no)
			(layer "B.CrtYd")
		)
		(fp_line
			(start 0.7239 1.9939)
			(end -0.7239 1.9939)
			(stroke
				(width 0.1)
				(type default)
			)
			(layer "B.Fab")
		)
		(fp_line
			(start 0.7239 -0.2159)
			(end 0.7239 1.9939)
			(stroke
				(width 0.1)
				(type default)
			)
			(layer "B.Fab")
		)
		(fp_line
			(start -0.7239 1.9939)
			(end -0.7239 -0.2159)
			(stroke
				(width 0.1)
				(type default)
			)
			(layer "B.Fab")
		)
		(fp_line
			(start -0.7239 -0.2159)
			(end 0.7239 -0.2159)
			(stroke
				(width 0.1)
				(type default)
			)
			(layer "B.Fab")
		)
		(pad "1" smd rect
			(at 0 0)
			(size 1.27 1.016)
			(layers "B.Cu" "B.Mask" "B.Paste")
			(net "PVDDQ_ABC")
		)
		(pad "2" smd rect
			(at 0 1.778)
			(size 1.27 1.016)
			(layers "B.Cu" "B.Mask" "B.Paste")
			(net "GND")
		)
		(zone
			(layer "B.Cu")
			(hatch none 0.5)
			(connect_pads
				(clearance 0)
			)
			(min_thickness 0.25)
			(keepout
				(tracks not_allowed)
				(vias allowed)
				(pads allowed)
				(copperpour not_allowed)
				(footprints allowed)
			)
			(placement
				(enabled no)
				(sheetname "")
			)
			(fill
				(thermal_gap 0.5)
				(thermal_bridge_width 0.5)
				(island_removal_mode 0)
			)
			(polygon
				(pts
					(xy 267.311886 -68.68414) (xy 268.581886 -68.68414) (xy 268.581886 -69.44614) (xy 267.311886 -69.44614)
				)
			)
		)
	)
)
